# T6G (Grand Teton) — schematic netlist excerpt (pin names and nets, part order shuffled) for the footprints in the layout excerpt that follows; sources: Cadence DE-HDL packaged netlist, KiCad conversion of 04192023_DAF0TMB3IC0_F0TG_MB_C_brd_V02_OCP.brd

R3286  Q_RES  1K 1% EMPTY  pkg 0402LF  page 111 : A = P3V3_AUX ; B = FM_P2E_SWB
PC451  Q_CAP  100NF 50V 10% X7R  pkg C0402  page 222 : A = PVDDIO_P1 ; B = GND

(kicad_pcb
	(version 20260206)
	(generator "pcbnew")
	(generator_version "10.0")
	(general
		(thickness 1.6)
		(legacy_teardrops no)
	)
	(paper "A4")
	(title_block
		(title "04192023_DAF0TMB3IC0_F0TG_MB_C_brd_V02_OCP.brd")
		(comment 1 "Grand Teton / footprints 4459-4460 of 8354")
	)
	(layers
		(0 "F.Cu" signal "TOP")
		(4 "In1.Cu" signal "GND")
		(6 "In2.Cu" signal "IN1")
		(8 "In3.Cu" signal "GND1")
		(10 "In4.Cu" signal "IN2")
		(12 "In5.Cu" signal "GND2")
		(14 "In6.Cu" signal "IN3")
		(16 "In7.Cu" signal "GND3")
		(18 "In8.Cu" signal "VCC")
		(20 "In9.Cu" signal "VCC1")
		(22 "In10.Cu" signal "GND4")
		(24 "In11.Cu" signal "IN4")
		(26 "In12.Cu" signal "GND5")
		(28 "In13.Cu" signal "IN5")
		(30 "In14.Cu" signal "GND6")
		(32 "In15.Cu" signal "IN6")
		(34 "In16.Cu" signal "GND7")
		(2 "B.Cu" signal "BOTTOM")
		(9 "F.Adhes" user "F.Adhesive")
		(11 "B.Adhes" user "B.Adhesive")
		(13 "F.Paste" user "Package Geometry/Pastemask Top")
		(15 "B.Paste" user "Package Geometry/Pastemask Bottom")
		(5 "F.SilkS" user "Ref Des/Silkscreen Top")
		(7 "B.SilkS" user "Ref Des/Silkscreen Bottom")
		(1 "F.Mask" user "Board Geometry/Soldermask Top")
		(3 "B.Mask" user "Board Geometry/Soldermask Bottom")
		(17 "Dwgs.User" user "User.Drawings")
		(19 "Cmts.User" user "User.Comments")
		(21 "Eco1.User" user "User.Eco1")
		(23 "Eco2.User" user "User.Eco2")
		(25 "Edge.Cuts" user "Board Geometry/Outline")
		(27 "Margin" user)
		(31 "F.CrtYd" user "Package Geometry/Place Bound Top")
		(29 "B.CrtYd" user "Package Geometry/Place Bound Bottom")
		(35 "F.Fab" user "Ref Des/Assembly Top")
		(33 "B.Fab" user "Ref Des/Assembly Bottom")
	)
	(footprint ""
		(layer "F.Cu")
		(at 23.916132 -332.638654 90)
		(property "Reference" "PC451"
			(at 0 0 90)
			(layer "F.SilkS")
			(hide yes)
			(effects
				(font
					(size 1.27 1.27)
				)
			)
		)
		(property "Value" ""
			(at 0 0 90)
			(layer "F.Fab")
			(effects
				(font
					(size 1.27 1.27)
				)
			)
		)
		(duplicate_pad_numbers_are_jumpers no)
		(fp_line
			(start 0.7874 -0.4064)
			(end 0.7874 0.4064)
			(stroke
				(width 0.1524)
				(type default)
			)
			(layer "F.SilkS")
		)
		(fp_line
			(start -0.7874 -0.4064)
			(end 0.7874 -0.4064)
			(stroke
				(width 0.1524)
				(type default)
			)
			(layer "F.SilkS")
		)
		(fp_line
			(start 0.7874 0.4064)
			(end -0.7874 0.4064)
			(stroke
				(width 0.1524)
				(type default)
			)
			(layer "F.SilkS")
		)
		(fp_line
			(start -0.7874 0.4064)
			(end -0.7874 -0.4064)
			(stroke
				(width 0.1524)
				(type default)
			)
			(layer "F.SilkS")
		)
		(fp_line
			(start -0.12065 -0.305054)
			(end -0.12065 -0.2794)
			(stroke
				(width 0.1)
				(type default)
			)
			(layer "F.Fab")
		)
		(fp_line
			(start -0.67945 -0.305054)
			(end -0.12065 -0.305054)
			(stroke
				(width 0.1)
				(type default)
			)
			(layer "F.Fab")
		)
		(fp_line
			(start 0.67945 -0.3048)
			(end 0.67945 0.3048)
			(stroke
				(width 0.1)
				(type default)
			)
			(layer "F.Fab")
		)
		(fp_line
			(start 0.12065 -0.3048)
			(end 0.67945 -0.3048)
			(stroke
				(width 0.1)
				(type default)
			)
			(layer "F.Fab")
		)
		(fp_line
			(start 0.12065 -0.2794)
			(end 0.12065 -0.3048)
			(stroke
				(width 0.1)
				(type default)
			)
			(layer "F.Fab")
		)
		(fp_line
			(start -0.12065 -0.2794)
			(end 0.12065 -0.2794)
			(stroke
				(width 0.1)
				(type default)
			)
			(layer "F.Fab")
		)
		(fp_line
			(start 0.120396 0.2794)
			(end -0.12065 0.2794)
			(stroke
				(width 0.1)
				(type default)
			)
			(layer "F.Fab")
		)
		(fp_line
			(start -0.12065 0.2794)
			(end -0.12065 0.3048)
			(stroke
				(width 0.1)
				(type default)
			)
			(layer "F.Fab")
		)
		(fp_line
			(start 0.67945 0.3048)
			(end 0.120396 0.3048)
			(stroke
				(width 0.1)
				(type default)
			)
			(layer "F.Fab")
		)
		(fp_line
			(start 0.120396 0.3048)
			(end 0.120396 0.2794)
			(stroke
				(width 0.1)
				(type default)
			)
			(layer "F.Fab")
		)
		(fp_line
			(start -0.12065 0.3048)
			(end -0.67945 0.3048)
			(stroke
				(width 0.1)
				(type default)
			)
			(layer "F.Fab")
		)
		(fp_line
			(start -0.67945 0.3048)
			(end -0.67945 -0.305054)
			(stroke
				(width 0.1)
				(type default)
			)
			(layer "F.Fab")
		)
		(pad "1" smd circle
			(at -0.40005 0 90)
			(size 0 0)
			(layers "F.Cu" "F.Mask" "F.Paste")
			(net "PVDDIO_P1")
		)
		(pad "2" smd circle
			(at 0.40005 0 90)
			(size 0 0)
			(layers "F.Cu" "F.Mask" "F.Paste")
			(net "GND")
		)
	)
	(footprint ""
		(layer "F.Cu")
		(at 37.402262 -429.790098 -90)
		(property "Reference" "R3286"
			(at 0 0 270)
			(layer "F.SilkS")
			(hide yes)
			(effects
				(font
					(size 1.27 1.27)
				)
			)
		)
		(property "Value" ""
			(at 0 0 270)
			(layer "F.Fab")
			(effects
				(font
					(size 1.27 1.27)
				)
			)
		)
		(duplicate_pad_numbers_are_jumpers no)
		(fp_line
			(start -0.7874 0.4064)
			(end -0.7874 -0.4064)
			(stroke
				(width 0.1524)
				(type default)
			)
			(layer "F.SilkS")
		)
		(fp_line
			(start 0.7874 0.4064)
			(end -0.7874 0.4064)
			(stroke
				(width 0.1524)
				(type default)
			)
			(layer "F.SilkS")
		)
		(fp_line
			(start -0.7874 -0.4064)
			(end 0.7874 -0.4064)
			(stroke
				(width 0.1524)
				(type default)
			)
			(layer "F.SilkS")
		)
		(fp_line
			(start 0.7874 -0.4064)
			(end 0.7874 0.4064)
			(stroke
				(width 0.1524)
				(type default)
			)
			(layer "F.SilkS")
		)
		(fp_line
			(start -0.67945 0.3048)
			(end -0.67945 -0.305054)
			(stroke
				(width 0.1)
				(type default)
			)
			(layer "F.Fab")
		)
		(fp_line
			(start -0.12065 0.3048)
			(end -0.67945 0.3048)
			(stroke
				(width 0.1)
				(type default)
			)
			(layer "F.Fab")
		)
		(fp_line
			(start 0.120396 0.3048)
			(end 0.120396 0.2794)
			(stroke
				(width 0.1)
				(type default)
			)
			(layer "F.Fab")
		)
		(fp_line
			(start 0.67945 0.3048)
			(end 0.120396 0.3048)
			(stroke
				(width 0.1)
				(type default)
			)
			(layer "F.Fab")
		)
		(fp_line
			(start -0.12065 0.2794)
			(end -0.12065 0.3048)
			(stroke
				(width 0.1)
				(type default)
			)
			(layer "F.Fab")
		)
		(fp_line
			(start 0.120396 0.2794)
			(end -0.12065 0.2794)
			(stroke
				(width 0.1)
				(type default)
			)
			(layer "F.Fab")
		)
		(fp_line
			(start -0.12065 -0.2794)
			(end 0.12065 -0.2794)
			(stroke
				(width 0.1)
				(type default)
			)
			(layer "F.Fab")
		)
		(fp_line
			(start 0.12065 -0.2794)
			(end 0.12065 -0.3048)
			(stroke
				(width 0.1)
				(type default)
			)
			(layer "F.Fab")
		)
		(fp_line
			(start 0.12065 -0.3048)
			(end 0.67945 -0.3048)
			(stroke
				(width 0.1)
				(type default)
			)
			(layer "F.Fab")
		)
		(fp_line
			(start 0.67945 -0.3048)
			(end 0.67945 0.3048)
			(stroke
				(width 0.1)
				(type default)
			)
			(layer "F.Fab")
		)
		(fp_line
			(start -0.67945 -0.305054)
			(end -0.12065 -0.305054)
			(stroke
				(width 0.1)
				(type default)
			)
			(layer "F.Fab")
		)
		(fp_line
			(start -0.12065 -0.305054)
			(end -0.12065 -0.2794)
			(stroke
				(width 0.1)
				(type default)
			)
			(layer "F.Fab")
		)
		(pad "1" smd circle
			(at -0.40005 0 270)
			(size 0 0)
			(layers "F.Cu" "F.Mask" "F.Paste")
			(net "P3V3_AUX")
		)
		(pad "2" smd circle
			(at 0.40005 0 270)
			(size 0 0)
			(layers "F.Cu" "F.Mask" "F.Paste")
			(net "FM_P2E_SWB")
		)
	)
)
